# T6G (Grand Teton) — schematic netlist excerpt (pin names and nets, part order shuffled) for the footprints in the layout excerpt that follows; sources: Cadence DE-HDL packaged netlist, KiCad conversion of 04192023_DAF0TMB3IC0_F0TG_MB_C_brd_V02_OCP.brd

C16  Q_CAP  0.1UF 25V 10% X7R  pkg 0402  page 125 : A = GPU_3V3IO_RSVD3_FFU_ISO ; B = GND

(kicad_pcb
	(version 20260206)
	(generator "pcbnew")
	(generator_version "10.0")
	(general
		(thickness 1.6)
		(legacy_teardrops no)
	)
	(paper "A4")
	(title_block
		(title "04192023_DAF0TMB3IC0_F0TG_MB_C_brd_V02_OCP.brd")
		(comment 1 "Grand Teton / footprints 1871-1871 of 8354")
	)
	(layers
		(0 "F.Cu" signal "TOP")
		(4 "In1.Cu" signal "GND")
		(6 "In2.Cu" signal "IN1")
		(8 "In3.Cu" signal "GND1")
		(10 "In4.Cu" signal "IN2")
		(12 "In5.Cu" signal "GND2")
		(14 "In6.Cu" signal "IN3")
		(16 "In7.Cu" signal "GND3")
		(18 "In8.Cu" signal "VCC")
		(20 "In9.Cu" signal "VCC1")
		(22 "In10.Cu" signal "GND4")
		(24 "In11.Cu" signal "IN4")
		(26 "In12.Cu" signal "GND5")
		(28 "In13.Cu" signal "IN5")
		(30 "In14.Cu" signal "GND6")
		(32 "In15.Cu" signal "IN6")
		(34 "In16.Cu" signal "GND7")
		(2 "B.Cu" signal "BOTTOM")
		(9 "F.Adhes" user "F.Adhesive")
		(11 "B.Adhes" user "B.Adhesive")
		(13 "F.Paste" user "Package Geometry/Pastemask Top")
		(15 "B.Paste" user "Package Geometry/Pastemask Bottom")
		(5 "F.SilkS" user "Ref Des/Silkscreen Top")
		(7 "B.SilkS" user "Ref Des/Silkscreen Bottom")
		(1 "F.Mask" user "Board Geometry/Soldermask Top")
		(3 "B.Mask" user "Board Geometry/Soldermask Bottom")
		(17 "Dwgs.User" user "User.Drawings")
		(19 "Cmts.User" user "User.Comments")
		(21 "Eco1.User" user "User.Eco1")
		(23 "Eco2.User" user "User.Eco2")
		(25 "Edge.Cuts" user "Board Geometry/Outline")
		(27 "Margin" user)
		(31 "F.CrtYd" user "Package Geometry/Place Bound Top")
		(29 "B.CrtYd" user "Package Geometry/Place Bound Bottom")
		(35 "F.Fab" user "Ref Des/Assembly Top")
		(33 "B.Fab" user "Ref Des/Assembly Bottom")
	)
	(footprint ""
		(layer "F.Cu")
		(at 302.523398 -430.2379 180)
		(property "Reference" "C16"
			(at 0 0 180)
			(layer "F.SilkS")
			(hide yes)
			(effects
				(font
					(size 1.27 1.27)
				)
			)
		)
		(property "Value" ""
			(at 0 0 180)
			(layer "F.Fab")
			(effects
				(font
					(size 1.27 1.27)
				)
			)
		)
		(duplicate_pad_numbers_are_jumpers no)
		(fp_line
			(start 0.7874 0.4064)
			(end -0.7874 0.4064)
			(stroke
				(width 0.1524)
				(type default)
			)
			(layer "F.SilkS")
		)
		(fp_line
			(start 0.7874 -0.4064)
			(end 0.7874 0.4064)
			(stroke
				(width 0.1524)
				(type default)
			)
			(layer "F.SilkS")
		)
		(fp_line
			(start -0.7874 0.4064)
			(end -0.7874 -0.4064)
			(stroke
				(width 0.1524)
				(type default)
			)
			(layer "F.SilkS")
		)
		(fp_line
			(start -0.7874 -0.4064)
			(end 0.7874 -0.4064)
			(stroke
				(width 0.1524)
				(type default)
			)
			(layer "F.SilkS")
		)
		(fp_line
			(start 0.67945 0.3048)
			(end 0.120396 0.3048)
			(stroke
				(width 0.1)
				(type default)
			)
			(layer "F.Fab")
		)
		(fp_line
			(start 0.67945 -0.3048)
			(end 0.67945 0.3048)
			(stroke
				(width 0.1)
				(type default)
			)
			(layer "F.Fab")
		)
		(fp_line
			(start 0.12065 -0.2794)
			(end 0.12065 -0.3048)
			(stroke
				(width 0.1)
				(type default)
			)
			(layer "F.Fab")
		)
		(fp_line
			(start 0.12065 -0.3048)
			(end 0.67945 -0.3048)
			(stroke
				(width 0.1)
				(type default)
			)
			(layer "F.Fab")
		)
		(fp_line
			(start 0.120396 0.3048)
			(end 0.120396 0.2794)
			(stroke
				(width 0.1)
				(type default)
			)
			(layer "F.Fab")
		)
		(fp_line
			(start 0.120396 0.2794)
			(end -0.12065 0.2794)
			(stroke
				(width 0.1)
				(type default)
			)
			(layer "F.Fab")
		)
		(fp_line
			(start -0.12065 0.3048)
			(end -0.67945 0.3048)
			(stroke
				(width 0.1)
				(type default)
			)
			(layer "F.Fab")
		)
		(fp_line
			(start -0.12065 0.2794)
			(end -0.12065 0.3048)
			(stroke
				(width 0.1)
				(type default)
			)
			(layer "F.Fab")
		)
		(fp_line
			(start -0.12065 -0.2794)
			(end 0.12065 -0.2794)
			(stroke
				(width 0.1)
				(type default)
			)
			(layer "F.Fab")
		)
		(fp_line
			(start -0.12065 -0.305054)
			(end -0.12065 -0.2794)
			(stroke
				(width 0.1)
				(type default)
			)
			(layer "F.Fab")
		)
		(fp_line
			(start -0.67945 0.3048)
			(end -0.67945 -0.305054)
			(stroke
				(width 0.1)
				(type default)
			)
			(layer "F.Fab")
		)
		(fp_line
			(start -0.67945 -0.305054)
			(end -0.12065 -0.305054)
			(stroke
				(width 0.1)
				(type default)
			)
			(layer "F.Fab")
		)
		(pad "1" smd circle
			(at -0.40005 0 180)
			(size 0 0)
			(layers "F.Cu" "F.Mask" "F.Paste")
			(net "GPU_3V3IO_RSVD3_FFU_ISO")
		)
		(pad "2" smd circle
			(at 0.40005 0 180)
			(size 0 0)
			(layers "F.Cu" "F.Mask" "F.Paste")
			(net "GND")
		)
	)
)
